# SCM (Grand Teton) — schematic netlist excerpt (pin names and nets, part order shuffled) for the footprints in the layout excerpt that follows; sources: Cadence DE-HDL packaged netlist, KiCad conversion of 12092022_DA0F0TMDCD0_F0T_Management_Board_D_brd_V3_OCP.brd

R238  Q_RES  4.7K 1% CHIP  pkg 0402LF  page 13 : A = P3V3_AUX ; B = SPI_BMC_TPM_CS2_R_N
PC251  Q_CAP  10UF 25V 10% X6S  pkg C0805  page 55 : A = SW_P1V2_AUX_FLT ; B = GND

(kicad_pcb
	(version 20260206)
	(generator "pcbnew")
	(generator_version "10.0")
	(general
		(thickness 1.6)
		(legacy_teardrops no)
	)
	(paper "A4")
	(title_block
		(title "12092022_DA0F0TMDCD0_F0T_Management_Board_D_brd_V3_OCP.brd")
		(comment 1 "Grand Teton / footprints 533-534 of 1440")
	)
	(layers
		(0 "F.Cu" signal "TOP")
		(4 "In1.Cu" signal "GND")
		(6 "In2.Cu" signal "IN1")
		(8 "In3.Cu" signal "GND1")
		(10 "In4.Cu" signal "IN2")
		(12 "In5.Cu" signal "VCC")
		(14 "In6.Cu" signal "VCC1")
		(16 "In7.Cu" signal "IN3")
		(18 "In8.Cu" signal "GND2")
		(20 "In9.Cu" signal "IN4")
		(22 "In10.Cu" signal "GND3")
		(2 "B.Cu" signal "BOTTOM")
		(9 "F.Adhes" user "F.Adhesive")
		(11 "B.Adhes" user "B.Adhesive")
		(13 "F.Paste" user "Package Geometry/Pastemask Top")
		(15 "B.Paste" user "Package Geometry/Pastemask Bottom")
		(5 "F.SilkS" user "Ref Des/Silkscreen Top")
		(7 "B.SilkS" user "Ref Des/Silkscreen Bottom")
		(1 "F.Mask" user "Board Geometry/Soldermask Top")
		(3 "B.Mask" user "Board Geometry/Soldermask Bottom")
		(17 "Dwgs.User" user "User.Drawings")
		(19 "Cmts.User" user "User.Comments")
		(21 "Eco1.User" user "User.Eco1")
		(23 "Eco2.User" user "User.Eco2")
		(25 "Edge.Cuts" user "Board Geometry/Outline")
		(27 "Margin" user)
		(31 "F.CrtYd" user "Package Geometry/Place Bound Top")
		(29 "B.CrtYd" user "Package Geometry/Place Bound Bottom")
		(35 "F.Fab" user "Ref Des/Assembly Top")
		(33 "B.Fab" user "Ref Des/Assembly Bottom")
	)
	(footprint ""
		(layer "F.Cu")
		(at 81.755996 -78.151228 180)
		(property "Reference" "PC251"
			(at 0 0 180)
			(layer "F.SilkS")
			(hide yes)
			(effects
				(font
					(size 1.27 1.27)
				)
			)
		)
		(property "Value" ""
			(at 0 0 180)
			(layer "F.Fab")
			(effects
				(font
					(size 1.27 1.27)
				)
			)
		)
		(duplicate_pad_numbers_are_jumpers no)
		(fp_line
			(start 1.651 0.8382)
			(end -1.651 0.8382)
			(stroke
				(width 0.1524)
				(type default)
			)
			(layer "F.SilkS")
		)
		(fp_line
			(start 1.651 -0.8382)
			(end 1.651 0.8382)
			(stroke
				(width 0.1524)
				(type default)
			)
			(layer "F.SilkS")
		)
		(fp_line
			(start 0 0.8382)
			(end 0 -0.8382)
			(stroke
				(width 0.1524)
				(type default)
			)
			(layer "F.SilkS")
		)
		(fp_line
			(start -1.651 0.8382)
			(end -1.651 -0.8382)
			(stroke
				(width 0.1524)
				(type default)
			)
			(layer "F.SilkS")
		)
		(fp_line
			(start -1.651 -0.8382)
			(end 1.651 -0.8382)
			(stroke
				(width 0.1524)
				(type default)
			)
			(layer "F.SilkS")
		)
		(fp_line
			(start 1.55956 0.7366)
			(end 1.55956 -0.7366)
			(stroke
				(width 0.1)
				(type default)
			)
			(layer "F.Fab")
		)
		(fp_line
			(start 1.55956 -0.7366)
			(end 1.524 -0.7366)
			(stroke
				(width 0.1)
				(type default)
			)
			(layer "F.Fab")
		)
		(fp_line
			(start 1.524 0.7366)
			(end 1.55956 0.7366)
			(stroke
				(width 0.1)
				(type default)
			)
			(layer "F.Fab")
		)
		(fp_line
			(start 1.524 -0.7366)
			(end -1.524 -0.7366)
			(stroke
				(width 0.1)
				(type default)
			)
			(layer "F.Fab")
		)
		(fp_line
			(start -1.524 0.7366)
			(end 1.524 0.7366)
			(stroke
				(width 0.1)
				(type default)
			)
			(layer "F.Fab")
		)
		(fp_line
			(start -1.524 -0.7366)
			(end -1.55956 -0.7366)
			(stroke
				(width 0.1)
				(type default)
			)
			(layer "F.Fab")
		)
		(fp_line
			(start -1.55956 0.7366)
			(end -1.524 0.7366)
			(stroke
				(width 0.1)
				(type default)
			)
			(layer "F.Fab")
		)
		(fp_line
			(start -1.55956 -0.7366)
			(end -1.55956 0.7366)
			(stroke
				(width 0.1)
				(type default)
			)
			(layer "F.Fab")
		)
		(pad "1" smd rect
			(at -0.94996 0)
			(size 1.1176 1.3716)
			(layers "F.Cu" "F.Mask" "F.Paste")
			(net "SW_P1V2_AUX_FLT")
		)
		(pad "2" smd rect
			(at 0.94996 0)
			(size 1.1176 1.3716)
			(layers "F.Cu" "F.Mask" "F.Paste")
			(net "GND")
		)
	)
	(footprint ""
		(layer "F.Cu")
		(at 68.4276 -71.882 -90)
		(property "Reference" "R238"
			(at 0 0 270)
			(layer "F.SilkS")
			(hide yes)
			(effects
				(font
					(size 1.27 1.27)
				)
			)
		)
		(property "Value" ""
			(at 0 0 270)
			(layer "F.Fab")
			(effects
				(font
					(size 1.27 1.27)
				)
			)
		)
		(duplicate_pad_numbers_are_jumpers no)
		(fp_line
			(start -0.7874 0.4064)
			(end -0.7874 -0.4064)
			(stroke
				(width 0.1524)
				(type default)
			)
			(layer "F.SilkS")
		)
		(fp_line
			(start 0.7874 0.4064)
			(end -0.7874 0.4064)
			(stroke
				(width 0.1524)
				(type default)
			)
			(layer "F.SilkS")
		)
		(fp_line
			(start -0.7874 -0.4064)
			(end 0.7874 -0.4064)
			(stroke
				(width 0.1524)
				(type default)
			)
			(layer "F.SilkS")
		)
		(fp_line
			(start 0.7874 -0.4064)
			(end 0.7874 0.4064)
			(stroke
				(width 0.1524)
				(type default)
			)
			(layer "F.SilkS")
		)
		(fp_line
			(start -0.67945 0.3048)
			(end -0.67945 -0.305054)
			(stroke
				(width 0.1)
				(type default)
			)
			(layer "F.Fab")
		)
		(fp_line
			(start -0.12065 0.3048)
			(end -0.67945 0.3048)
			(stroke
				(width 0.1)
				(type default)
			)
			(layer "F.Fab")
		)
		(fp_line
			(start 0.120396 0.3048)
			(end 0.120396 0.2794)
			(stroke
				(width 0.1)
				(type default)
			)
			(layer "F.Fab")
		)
		(fp_line
			(start 0.67945 0.3048)
			(end 0.120396 0.3048)
			(stroke
				(width 0.1)
				(type default)
			)
			(layer "F.Fab")
		)
		(fp_line
			(start -0.12065 0.2794)
			(end -0.12065 0.3048)
			(stroke
				(width 0.1)
				(type default)
			)
			(layer "F.Fab")
		)
		(fp_line
			(start 0.120396 0.2794)
			(end -0.12065 0.2794)
			(stroke
				(width 0.1)
				(type default)
			)
			(layer "F.Fab")
		)
		(fp_line
			(start -0.12065 -0.2794)
			(end 0.12065 -0.2794)
			(stroke
				(width 0.1)
				(type default)
			)
			(layer "F.Fab")
		)
		(fp_line
			(start 0.12065 -0.2794)
			(end 0.12065 -0.3048)
			(stroke
				(width 0.1)
				(type default)
			)
			(layer "F.Fab")
		)
		(fp_line
			(start 0.12065 -0.3048)
			(end 0.67945 -0.3048)
			(stroke
				(width 0.1)
				(type default)
			)
			(layer "F.Fab")
		)
		(fp_line
			(start 0.67945 -0.3048)
			(end 0.67945 0.3048)
			(stroke
				(width 0.1)
				(type default)
			)
			(layer "F.Fab")
		)
		(fp_line
			(start -0.67945 -0.305054)
			(end -0.12065 -0.305054)
			(stroke
				(width 0.1)
				(type default)
			)
			(layer "F.Fab")
		)
		(fp_line
			(start -0.12065 -0.305054)
			(end -0.12065 -0.2794)
			(stroke
				(width 0.1)
				(type default)
			)
			(layer "F.Fab")
		)
		(pad "1" smd circle
			(at -0.40005 0 270)
			(size 0 0)
			(layers "F.Cu" "F.Mask" "F.Paste")
			(net "P3V3_AUX")
		)
		(pad "2" smd circle
			(at 0.40005 0 270)
			(size 0 0)
			(layers "F.Cu" "F.Mask" "F.Paste")
			(net "SPI_BMC_TPM_CS2_R_N")
		)
	)
)
